(kicad_pcb
	(version 20260206)
	(generator "pcbnew")
	(generator_version "10.0")
	(general
		(thickness 1.6)
		(legacy_teardrops no)
	)
	(paper "A4")
	(title_block
		(title "v1-chassis-manager — T6M_CM_d_v01_1031_1645.brd")
		(comment 1 "Open CloudServer (Microsoft) / footprint 1511 of 2512 (U128), pads 1-100 of 100")
	)
	(layers
		(0 "F.Cu" signal "TOP")
		(4 "In1.Cu" signal "GND1")
		(6 "In2.Cu" signal "IN1")
		(8 "In3.Cu" signal "VCC1")
		(10 "In4.Cu" signal "VCC2")
		(12 "In5.Cu" signal "GND2")
		(14 "In6.Cu" signal "IN2")
		(16 "In7.Cu" signal "IN3")
		(18 "In8.Cu" signal "GND3")
		(2 "B.Cu" signal "BOTTOM")
		(9 "F.Adhes" user "F.Adhesive")
		(11 "B.Adhes" user "B.Adhesive")
		(13 "F.Paste" user "Package Geometry/Pastemask Top")
		(15 "B.Paste" user "Package Geometry/Pastemask Bottom")
		(5 "F.SilkS" user "Ref Des/Silkscreen Top")
		(7 "B.SilkS" user "Ref Des/Silkscreen Bottom")
		(1 "F.Mask" user "Board Geometry/Soldermask Top")
		(3 "B.Mask" user "Board Geometry/Soldermask Bottom")
		(17 "Dwgs.User" user "User.Drawings")
		(19 "Cmts.User" user "User.Comments")
		(21 "Eco1.User" user "User.Eco1")
		(23 "Eco2.User" user "User.Eco2")
		(25 "Edge.Cuts" user "Board Geometry/Outline")
		(27 "Margin" user)
		(31 "F.CrtYd" user "Package Geometry/Place Bound Top")
		(29 "B.CrtYd" user "Package Geometry/Place Bound Bottom")
		(35 "F.Fab" user "Ref Des/Assembly Top")
		(33 "B.Fab" user "Ref Des/Assembly Bottom")
	)
	(footprint ""
		(layer "F.Cu")
		(at 79.99476 -172.124624 -90)
		(property "Reference" "U128"
			(at 10.616946 -4.361942 0)
			(unlocked yes)
			(layer "F.SilkS")
			(effects
				(font
					(size 0.7874 0.5842)
					(thickness 0.1524)
				)
				(justify left)
			)
		)
		(property "Value" ""
			(at 0 0 270)
			(layer "F.Fab")
			(effects
				(font
					(size 1.27 1.27)
				)
			)
		)
		(duplicate_pad_numbers_are_jumpers no)
		(pad "1" smd rect
			(at -7.750048 -5.999988)
			(size 0.2794 1.4986)
			(layers "F.Cu" "F.Mask" "F.Paste")
			(net "CPLD_UART_DTR_P4_N")
		)
		(pad "2" smd rect
			(at -7.750048 -5.500116)
			(size 0.2794 1.4986)
			(layers "F.Cu" "F.Mask" "F.Paste")
			(net "UART_SW_S0_N")
		)
		(pad "3" smd rect
			(at -7.750048 -4.99999)
			(size 0.2794 1.4986)
			(layers "F.Cu" "F.Mask" "F.Paste")
			(net "UART_SW_S1_N")
		)
		(pad "4" smd rect
			(at -7.750048 -4.500118)
			(size 0.2794 1.4986)
			(layers "F.Cu" "F.Mask" "F.Paste")
			(net "UART_SW_S2_N")
		)
		(pad "5" smd rect
			(at -7.750048 -3.999992)
			(size 0.2794 1.4986)
			(layers "F.Cu" "F.Mask" "F.Paste")
			(net "UART_SW_S3_N")
		)
		(pad "6" smd rect
			(at -7.750048 -3.50012)
			(size 0.2794 1.4986)
			(layers "F.Cu" "F.Mask" "F.Paste")
			(net "UART_SW_S4_N")
		)
		(pad "7" smd rect
			(at -7.750048 -2.999994)
			(size 0.2794 1.4986)
			(layers "F.Cu" "F.Mask" "F.Paste")
			(net "UART_SW_S5_N")
		)
		(pad "8" smd rect
			(at -7.750048 -2.500122)
			(size 0.2794 1.4986)
			(layers "F.Cu" "F.Mask" "F.Paste")
			(net "SDC_RST_N")
		)
		(pad "9" smd rect
			(at -7.750048 -1.999996)
			(size 0.2794 1.4986)
			(layers "F.Cu" "F.Mask" "F.Paste")
			(net "P3V3_NODE1")
		)
		(pad "10" smd rect
			(at -7.750048 -1.500124)
			(size 0.2794 1.4986)
			(layers "F.Cu" "F.Mask" "F.Paste")
			(net "GND")
		)
		(pad "11" smd rect
			(at -7.750048 -0.999998)
			(size 0.2794 1.4986)
			(layers "F.Cu" "F.Mask" "F.Paste")
			(net "GND")
		)
		(pad "12" smd rect
			(at -7.750048 -0.499872)
			(size 0.2794 1.4986)
			(layers "F.Cu" "F.Mask" "F.Paste")
			(net "CPLD_WDT3")
		)
		(pad "13" smd rect
			(at -7.750048 0)
			(size 0.2794 1.4986)
			(layers "F.Cu" "F.Mask" "F.Paste")
			(net "P3V3_NODE1")
		)
		(pad "14" smd rect
			(at -7.750048 0.499872)
			(size 0.2794 1.4986)
			(layers "F.Cu" "F.Mask" "F.Paste")
			(net "CPU_RSV_1")
		)
		(pad "15" smd rect
			(at -7.750048 0.999998)
			(size 0.2794 1.4986)
			(layers "F.Cu" "F.Mask" "F.Paste")
			(net "UART_TX_P4")
		)
		(pad "16" smd rect
			(at -7.750048 1.500124)
			(size 0.2794 1.4986)
			(layers "F.Cu" "F.Mask" "F.Paste")
			(net "UART_RX_P4")
		)
		(pad "17" smd rect
			(at -7.750048 1.999996)
			(size 0.2794 1.4986)
			(layers "F.Cu" "F.Mask" "F.Paste")
			(net "UART_DTR_P4_N")
		)
		(pad "18" smd rect
			(at -7.750048 2.500122)
			(size 0.2794 1.4986)
			(layers "F.Cu" "F.Mask" "F.Paste")
			(net "UART_RTS_P4_N")
		)
		(pad "19" smd rect
			(at -7.750048 2.999994)
			(size 0.2794 1.4986)
			(layers "F.Cu" "F.Mask" "F.Paste")
			(net "UART_RI_P4_N")
		)
		(pad "20" smd rect
			(at -7.750048 3.50012)
			(size 0.2794 1.4986)
			(layers "F.Cu" "F.Mask" "F.Paste")
			(net "UART_SDC_TX")
		)
		(pad "21" smd rect
			(at -7.750048 3.999992)
			(size 0.2794 1.4986)
			(layers "F.Cu" "F.Mask" "F.Paste")
			(net "UART_SDC_RX")
		)
		(pad "22" smd rect
			(at -7.750048 4.500118)
			(size 0.2794 1.4986)
			(layers "F.Cu" "F.Mask" "F.Paste")
			(net "JTAG_CPLD2_TMS")
		)
		(pad "23" smd rect
			(at -7.750048 4.99999)
			(size 0.2794 1.4986)
			(layers "F.Cu" "F.Mask" "F.Paste")
			(net "JTAG_CPLD2_TDI")
		)
		(pad "24" smd rect
			(at -7.750048 5.500116)
			(size 0.2794 1.4986)
			(layers "F.Cu" "F.Mask" "F.Paste")
			(net "JTAG_CPLD2_TCK")
		)
		(pad "25" smd rect
			(at -7.750048 5.999988)
			(size 0.2794 1.4986)
			(layers "F.Cu" "F.Mask" "F.Paste")
			(net "JTAG_CPLD2_TDO")
		)
		(pad "26" smd rect
			(at -5.999988 7.750048 270)
			(size 0.2794 1.4986)
			(layers "F.Cu" "F.Mask" "F.Paste")
			(net "UART_T1_NODE1_TXD")
		)
		(pad "27" smd rect
			(at -5.500116 7.750048 270)
			(size 0.2794 1.4986)
			(layers "F.Cu" "F.Mask" "F.Paste")
			(net "UART_T1_NODE1_RXD")
		)
		(pad "28" smd rect
			(at -4.99999 7.750048 270)
			(size 0.2794 1.4986)
			(layers "F.Cu" "F.Mask" "F.Paste")
			(net "UART_T1_NODE2_TXD")
		)
		(pad "29" smd rect
			(at -4.500118 7.750048 270)
			(size 0.2794 1.4986)
			(layers "F.Cu" "F.Mask" "F.Paste")
			(net "UART_T1_NODE2_RXD")
		)
		(pad "30" smd rect
			(at -3.999992 7.750048 270)
			(size 0.2794 1.4986)
			(layers "F.Cu" "F.Mask" "F.Paste")
			(net "WDT_LED")
		)
		(pad "31" smd rect
			(at -3.50012 7.750048 270)
			(size 0.2794 1.4986)
			(layers "F.Cu" "F.Mask" "F.Paste")
			(net "P3V3_NODE1")
		)
		(pad "32" smd rect
			(at -2.999994 7.750048 270)
			(size 0.2794 1.4986)
			(layers "F.Cu" "F.Mask" "F.Paste")
			(net "GND")
		)
		(pad "33" smd rect
			(at -2.500122 7.750048 270)
			(size 0.2794 1.4986)
			(layers "F.Cu" "F.Mask" "F.Paste")
			(net "UART_T1_NODE3_TXD")
		)
		(pad "34" smd rect
			(at -1.999996 7.750048 270)
			(size 0.2794 1.4986)
			(layers "F.Cu" "F.Mask" "F.Paste")
			(net "UART_T1_NODE3_RXD")
		)
		(pad "35" smd rect
			(at -1.500124 7.750048 270)
			(size 0.2794 1.4986)
			(layers "F.Cu" "F.Mask" "F.Paste")
			(net "UART_T1_NODE4_TXD")
		)
		(pad "36" smd rect
			(at -0.999998 7.750048 270)
			(size 0.2794 1.4986)
			(layers "F.Cu" "F.Mask" "F.Paste")
			(net "UART_T1_NODE4_RXD")
		)
		(pad "37" smd rect
			(at -0.499872 7.750048 270)
			(size 0.2794 1.4986)
			(layers "F.Cu" "F.Mask" "F.Paste")
			(net "UART_T2_NODE1_TXD")
		)
		(pad "38" smd rect
			(at 0 7.750048 270)
			(size 0.2794 1.4986)
			(layers "F.Cu" "F.Mask" "F.Paste")
			(net "UART_T2_NODE1_RXD")
		)
		(pad "39" smd rect
			(at 0.499872 7.750048 270)
			(size 0.2794 1.4986)
			(layers "F.Cu" "F.Mask" "F.Paste")
			(net "UART_T2_NODE2_TXD")
		)
		(pad "40" smd rect
			(at 0.999998 7.750048 270)
			(size 0.2794 1.4986)
			(layers "F.Cu" "F.Mask" "F.Paste")
			(net "UART_T2_NODE2_RXD")
		)
		(pad "41" smd rect
			(at 1.500124 7.750048 270)
			(size 0.2794 1.4986)
			(layers "F.Cu" "F.Mask" "F.Paste")
			(net "UART_T2_NODE3_TXD")
		)
		(pad "42" smd rect
			(at 1.999996 7.750048 270)
			(size 0.2794 1.4986)
			(layers "F.Cu" "F.Mask" "F.Paste")
			(net "UART_T2_NODE3_RXD")
		)
		(pad "43" smd rect
			(at 2.500122 7.750048 270)
			(size 0.2794 1.4986)
			(layers "F.Cu" "F.Mask" "F.Paste")
			(net "CPLD_WDT1")
		)
		(pad "44" smd rect
			(at 2.999994 7.750048 270)
			(size 0.2794 1.4986)
			(layers "F.Cu" "F.Mask" "F.Paste")
			(net "CPLD_WDT2")
		)
		(pad "45" smd rect
			(at 3.50012 7.750048 270)
			(size 0.2794 1.4986)
			(layers "F.Cu" "F.Mask" "F.Paste")
			(net "P3V3_NODE1")
		)
		(pad "46" smd rect
			(at 3.999992 7.750048 270)
			(size 0.2794 1.4986)
			(layers "F.Cu" "F.Mask" "F.Paste")
			(net "GND")
		)
		(pad "47" smd rect
			(at 4.500118 7.750048 270)
			(size 0.2794 1.4986)
			(layers "F.Cu" "F.Mask" "F.Paste")
			(net "UART_T2_NODE4_TXD")
		)
		(pad "48" smd rect
			(at 4.99999 7.750048 270)
			(size 0.2794 1.4986)
			(layers "F.Cu" "F.Mask" "F.Paste")
			(net "UART_T2_NODE4_RXD")
		)
		(pad "49" smd rect
			(at 5.500116 7.750048 270)
			(size 0.2794 1.4986)
			(layers "F.Cu" "F.Mask" "F.Paste")
			(net "CPLD2_RSV1")
		)
		(pad "50" smd rect
			(at 5.999988 7.750048 270)
			(size 0.2794 1.4986)
			(layers "F.Cu" "F.Mask" "F.Paste")
			(net "CPLD2_RSV2")
		)
		(pad "51" smd rect
			(at 7.750048 5.999988)
			(size 0.2794 1.4986)
			(layers "F.Cu" "F.Mask" "F.Paste")
			(net "CPLD2_RSV3")
		)
		(pad "52" smd rect
			(at 7.750048 5.500116)
			(size 0.2794 1.4986)
			(layers "F.Cu" "F.Mask" "F.Paste")
			(net "UART_T3_NODE1_TXD")
		)
		(pad "53" smd rect
			(at 7.750048 4.99999)
			(size 0.2794 1.4986)
			(layers "F.Cu" "F.Mask" "F.Paste")
			(net "UART_T3_NODE1_RXD")
		)
		(pad "54" smd rect
			(at 7.750048 4.500118)
			(size 0.2794 1.4986)
			(layers "F.Cu" "F.Mask" "F.Paste")
			(net "UART_T3_NODE2_TXD")
		)
		(pad "55" smd rect
			(at 7.750048 3.999992)
			(size 0.2794 1.4986)
			(layers "F.Cu" "F.Mask" "F.Paste")
			(net "UART_T3_NODE2_RXD")
		)
		(pad "56" smd rect
			(at 7.750048 3.50012)
			(size 0.2794 1.4986)
			(layers "F.Cu" "F.Mask" "F.Paste")
			(net "UART_T3_NODE3_TXD")
		)
		(pad "57" smd rect
			(at 7.750048 2.999994)
			(size 0.2794 1.4986)
			(layers "F.Cu" "F.Mask" "F.Paste")
			(net "UART_T3_NODE3_RXD")
		)
		(pad "58" smd rect
			(at 7.750048 2.500122)
			(size 0.2794 1.4986)
			(layers "F.Cu" "F.Mask" "F.Paste")
			(net "TACKOVER_EN_N")
		)
		(pad "59" smd rect
			(at 7.750048 1.999996)
			(size 0.2794 1.4986)
			(layers "F.Cu" "F.Mask" "F.Paste")
			(net "P3V3_NODE1")
		)
		(pad "60" smd rect
			(at 7.750048 1.500124)
			(size 0.2794 1.4986)
			(layers "F.Cu" "F.Mask" "F.Paste")
			(net "GND")
		)
		(pad "61" smd rect
			(at 7.750048 0.999998)
			(size 0.2794 1.4986)
			(layers "F.Cu" "F.Mask" "F.Paste")
			(net "FAN_MAX_CTRL")
		)
		(pad "62" smd rect
			(at 7.750048 0.499872)
			(size 0.2794 1.4986)
			(layers "F.Cu" "F.Mask" "F.Paste")
			(net "CMC_CPLD_RSV1")
		)
		(pad "63" smd rect
			(at 7.750048 0)
			(size 0.2794 1.4986)
			(layers "F.Cu" "F.Mask" "F.Paste")
			(net "P3V3_NODE1")
		)
		(pad "64" smd rect
			(at 7.750048 -0.499872)
			(size 0.2794 1.4986)
			(layers "F.Cu" "F.Mask" "F.Paste")
			(net "CLK_33K_CPLD23")
		)
		(pad "65" smd rect
			(at 7.750048 -0.999998)
			(size 0.2794 1.4986)
			(layers "F.Cu" "F.Mask" "F.Paste")
			(net "GND")
		)
		(pad "66" smd rect
			(at 7.750048 -1.500124)
			(size 0.2794 1.4986)
			(layers "F.Cu" "F.Mask" "F.Paste")
			(net "UART_T3_NODE4_TXD")
		)
		(pad "67" smd rect
			(at 7.750048 -1.999996)
			(size 0.2794 1.4986)
			(layers "F.Cu" "F.Mask" "F.Paste")
			(net "UART_T3_NODE4_RXD")
		)
		(pad "68" smd rect
			(at 7.750048 -2.500122)
			(size 0.2794 1.4986)
			(layers "F.Cu" "F.Mask" "F.Paste")
			(net "UART_T4_NODE1_TXD")
		)
		(pad "69" smd rect
			(at 7.750048 -2.999994)
			(size 0.2794 1.4986)
			(layers "F.Cu" "F.Mask" "F.Paste")
			(net "UART_T4_NODE1_RXD")
		)
		(pad "70" smd rect
			(at 7.750048 -3.50012)
			(size 0.2794 1.4986)
			(layers "F.Cu" "F.Mask" "F.Paste")
			(net "UART_T4_NODE2_TXD")
		)
		(pad "71" smd rect
			(at 7.750048 -3.999992)
			(size 0.2794 1.4986)
			(layers "F.Cu" "F.Mask" "F.Paste")
			(net "UART_T4_NODE2_RXD")
		)
		(pad "72" smd rect
			(at 7.750048 -4.500118)
			(size 0.2794 1.4986)
			(layers "F.Cu" "F.Mask" "F.Paste")
			(net "UART_T4_NODE3_TXD")
		)
		(pad "73" smd rect
			(at 7.750048 -4.99999)
			(size 0.2794 1.4986)
			(layers "F.Cu" "F.Mask" "F.Paste")
			(net "UART_T4_NODE3_RXD")
		)
		(pad "74" smd rect
			(at 7.750048 -5.500116)
			(size 0.2794 1.4986)
			(layers "F.Cu" "F.Mask" "F.Paste")
			(net "UART_T4_NODE4_TXD")
		)
		(pad "75" smd rect
			(at 7.750048 -5.999988)
			(size 0.2794 1.4986)
			(layers "F.Cu" "F.Mask" "F.Paste")
			(net "UART_T4_NODE4_RXD")
		)
		(pad "76" smd rect
			(at 5.999988 -7.750048 270)
			(size 0.2794 1.4986)
			(layers "F.Cu" "F.Mask" "F.Paste")
			(net "UART_T5_NODE1_TXD")
		)
		(pad "77" smd rect
			(at 5.500116 -7.750048 270)
			(size 0.2794 1.4986)
			(layers "F.Cu" "F.Mask" "F.Paste")
			(net "UART_T5_NODE1_RXD")
		)
		(pad "78" smd rect
			(at 4.99999 -7.750048 270)
			(size 0.2794 1.4986)
			(layers "F.Cu" "F.Mask" "F.Paste")
			(net "CPLD_FAN_MAX_CTRL")
		)
		(pad "79" smd rect
			(at 4.500118 -7.750048 270)
			(size 0.2794 1.4986)
			(layers "F.Cu" "F.Mask" "F.Paste")
			(net "GND")
		)
		(pad "80" smd rect
			(at 3.999992 -7.750048 270)
			(size 0.2794 1.4986)
			(layers "F.Cu" "F.Mask" "F.Paste")
			(net "P3V3_NODE1")
		)
		(pad "81" smd rect
			(at 3.50012 -7.750048 270)
			(size 0.2794 1.4986)
			(layers "F.Cu" "F.Mask" "F.Paste")
			(net "UART_T5_NODE2_TXD")
		)
		(pad "82" smd rect
			(at 2.999994 -7.750048 270)
			(size 0.2794 1.4986)
			(layers "F.Cu" "F.Mask" "F.Paste")
			(net "UART_T5_NODE2_RXD")
		)
		(pad "83" smd rect
			(at 2.500122 -7.750048 270)
			(size 0.2794 1.4986)
			(layers "F.Cu" "F.Mask" "F.Paste")
			(net "UART_T5_NODE3_TXD")
		)
		(pad "84" smd rect
			(at 1.999996 -7.750048 270)
			(size 0.2794 1.4986)
			(layers "F.Cu" "F.Mask" "F.Paste")
			(net "UART_T5_NODE3_RXD")
		)
		(pad "85" smd rect
			(at 1.500124 -7.750048 270)
			(size 0.2794 1.4986)
			(layers "F.Cu" "F.Mask" "F.Paste")
			(net "UART_T5_NODE4_TXD")
		)
		(pad "86" smd rect
			(at 0.999998 -7.750048 270)
			(size 0.2794 1.4986)
			(layers "F.Cu" "F.Mask" "F.Paste")
			(net "UART_T5_NODE4_RXD")
		)
		(pad "87" smd rect
			(at 0.499872 -7.750048 270)
			(size 0.2794 1.4986)
			(layers "F.Cu" "F.Mask" "F.Paste")
			(net "UART_T6_NODE1_TXD")
		)
		(pad "88" smd rect
			(at 0 -7.750048 270)
			(size 0.2794 1.4986)
			(layers "F.Cu" "F.Mask" "F.Paste")
			(net "UART_T6_NODE1_RXD")
		)
		(pad "89" smd rect
			(at -0.499872 -7.750048 270)
			(size 0.2794 1.4986)
			(layers "F.Cu" "F.Mask" "F.Paste")
			(net "UART_T6_NODE2_TXD")
		)
		(pad "90" smd rect
			(at -0.999998 -7.750048 270)
			(size 0.2794 1.4986)
			(layers "F.Cu" "F.Mask" "F.Paste")
			(net "UART_T6_NODE2_RXD")
		)
		(pad "91" smd rect
			(at -1.500124 -7.750048 270)
			(size 0.2794 1.4986)
			(layers "F.Cu" "F.Mask" "F.Paste")
			(net "UART_T6_NODE3_TXD")
		)
		(pad "92" smd rect
			(at -1.999996 -7.750048 270)
			(size 0.2794 1.4986)
			(layers "F.Cu" "F.Mask" "F.Paste")
			(net "UART_T6_NODE3_RXD")
		)
		(pad "93" smd rect
			(at -2.500122 -7.750048 270)
			(size 0.2794 1.4986)
			(layers "F.Cu" "F.Mask" "F.Paste")
			(net "GND")
		)
		(pad "94" smd rect
			(at -2.999994 -7.750048 270)
			(size 0.2794 1.4986)
			(layers "F.Cu" "F.Mask" "F.Paste")
			(net "P3V3_NODE1")
		)
		(pad "95" smd rect
			(at -3.50012 -7.750048 270)
			(size 0.2794 1.4986)
			(layers "F.Cu" "F.Mask" "F.Paste")
			(net "UART_T6_NODE4_TXD")
		)
		(pad "96" smd rect
			(at -3.999992 -7.750048 270)
			(size 0.2794 1.4986)
			(layers "F.Cu" "F.Mask" "F.Paste")
			(net "UART_T6_NODE4_RXD")
		)
		(pad "97" smd rect
			(at -4.500118 -7.750048 270)
			(size 0.2794 1.4986)
			(layers "F.Cu" "F.Mask" "F.Paste")
			(net "CPLD_UART_RTS_P4_N")
		)
		(pad "98" smd rect
			(at -4.99999 -7.750048 270)
			(size 0.2794 1.4986)
			(layers "F.Cu" "F.Mask" "F.Paste")
			(net "CPLD_UART_RI_P4_N")
		)
		(pad "99" smd rect
			(at -5.500116 -7.750048 270)
			(size 0.2794 1.4986)
			(layers "F.Cu" "F.Mask" "F.Paste")
			(net "CPLD_UART_RX_P4")
		)
		(pad "100" smd rect
			(at -5.999988 -7.750048 270)
			(size 0.2794 1.4986)
			(layers "F.Cu" "F.Mask" "F.Paste")
			(net "CPLD_UART_TX_P4")
		)
	)
)
